(kicad_pcb
	(version 20260206)
	(generator "pcbnew")
	(generator_version "10.0")
	(general
		(thickness 1.6)
		(legacy_teardrops no)
	)
	(paper "A4")
	(title_block
		(title "Bryce Canyon_SCC_16316-1_OCP.brd")
		(comment 1 "Bryce Canyon / footprints 511-517 of 1561")
	)
	(layers
		(0 "F.Cu" signal "TOP")
		(4 "In1.Cu" signal "L2GND")
		(6 "In2.Cu" signal "L3")
		(8 "In3.Cu" signal "L4VCC")
		(10 "In4.Cu" signal "L5VCC")
		(12 "In5.Cu" signal "L6")
		(14 "In6.Cu" signal "L7GND")
		(2 "B.Cu" signal "BOTTOM")
		(9 "F.Adhes" user "F.Adhesive")
		(11 "B.Adhes" user "B.Adhesive")
		(13 "F.Paste" user "Package Geometry/Pastemask Top")
		(15 "B.Paste" user "Package Geometry/Pastemask Bottom")
		(5 "F.SilkS" user "Ref Des/Silkscreen Top")
		(7 "B.SilkS" user "Ref Des/Silkscreen Bottom")
		(1 "F.Mask" user "Board Geometry/Soldermask Top")
		(3 "B.Mask" user "Board Geometry/Soldermask Bottom")
		(17 "Dwgs.User" user "User.Drawings")
		(19 "Cmts.User" user "User.Comments")
		(21 "Eco1.User" user "User.Eco1")
		(23 "Eco2.User" user "User.Eco2")
		(25 "Edge.Cuts" user "Board Geometry/Outline")
		(27 "Margin" user)
		(31 "F.CrtYd" user "Package Geometry/Place Bound Top")
		(29 "B.CrtYd" user "Package Geometry/Place Bound Bottom")
		(35 "F.Fab" user "Ref Des/Assembly Top")
		(33 "B.Fab" user "Ref Des/Assembly Bottom")
	)
	(footprint ""
		(layer "F.Cu")
		(at 175.48606 -105.47858)
		(property "Reference" "Q11"
			(at 0 0 0)
			(layer "F.SilkS")
			(hide yes)
			(effects
				(font
					(size 1.27 1.27)
				)
			)
		)
		(property "Value" "SSM3K324R-GP"
			(at 0.127 -8.9662 0)
			(unlocked yes)
			(layer "F.Fab")
			(hide yes)
			(effects
				(font
					(size 1.016 1.016)
					(thickness 0.1524)
				)
			)
		)
		(property "Device Type" "SOT23DGS2D4H35"
			(at 0.127 -10.4902 0)
			(unlocked yes)
			(layer "F.Fab")
			(hide yes)
			(effects
				(font
					(size 1.016 1.016)
					(thickness 0.1524)
				)
			)
		)
		(duplicate_pad_numbers_are_jumpers no)
		(fp_line
			(start -1.651 -1.778)
			(end -1.651 1.778)
			(stroke
				(width 0.1524)
				(type default)
			)
			(layer "F.SilkS")
		)
		(fp_line
			(start -1.651 1.778)
			(end 1.651 1.778)
			(stroke
				(width 0.1524)
				(type default)
			)
			(layer "F.SilkS")
		)
		(fp_line
			(start 1.651 -1.778)
			(end -1.651 -1.778)
			(stroke
				(width 0.1524)
				(type default)
			)
			(layer "F.SilkS")
		)
		(fp_line
			(start 1.651 1.778)
			(end 1.651 -1.778)
			(stroke
				(width 0.1524)
				(type default)
			)
			(layer "F.SilkS")
		)
		(fp_poly
			(pts
				(xy -1.778 1.8796) (xy -1.778 -1.8796) (xy 1.778 -1.8796) (xy 1.778 1.8796)
			)
			(stroke
				(width 0)
				(type default)
			)
			(fill no)
			(layer "F.CrtYd")
		)
		(fp_poly
			(pts
				(xy -1.778 1.8796) (xy -1.778 -1.8796) (xy 1.778 -1.8796) (xy 1.778 1.8796)
			)
			(stroke
				(width 0)
				(type default)
			)
			(fill no)
			(layer "F.Fab")
		)
		(pad "D" smd custom
			(at 0 -0.9525)
			(size 0.1905 0.1905)
			(layers "F.Cu" "F.Mask" "F.Paste")
			(net "P12V_STBY_Q12_G")
			(options
				(clearance outline)
				(anchor circle)
			)
			(primitives
				(gr_poly
					(pts
						(arc
							(start -0.1778 0.5715)
							(mid -0.321484 0.511984)
							(end -0.381 0.3683)
						)
						(arc
							(start -0.381 -0.3683)
							(mid -0.321484 -0.511984)
							(end -0.1778 -0.5715)
						)
						(arc
							(start 0.1778 -0.5715)
							(mid 0.321484 -0.511984)
							(end 0.381 -0.3683)
						)
						(arc
							(start 0.381 0.3683)
							(mid 0.321484 0.511984)
							(end 0.1778 0.5715)
						)
					)
					(width 0)
					(fill yes)
				)
			)
		)
		(pad "G" smd custom
			(at -0.98425 0.9525)
			(size 0.1905 0.1905)
			(layers "F.Cu" "F.Mask" "F.Paste")
			(net "P1V8_C_G")
			(options
				(clearance outline)
				(anchor circle)
			)
			(primitives
				(gr_poly
					(pts
						(arc
							(start -0.1778 0.5715)
							(mid -0.321484 0.511984)
							(end -0.381 0.3683)
						)
						(arc
							(start -0.381 -0.3683)
							(mid -0.321484 -0.511984)
							(end -0.1778 -0.5715)
						)
						(arc
							(start 0.1778 -0.5715)
							(mid 0.321484 -0.511984)
							(end 0.381 -0.3683)
						)
						(arc
							(start 0.381 0.3683)
							(mid 0.321484 0.511984)
							(end 0.1778 0.5715)
						)
					)
					(width 0)
					(fill yes)
				)
			)
		)
		(pad "S" smd custom
			(at 0.98425 0.9525)
			(size 0.1905 0.1905)
			(layers "F.Cu" "F.Mask" "F.Paste")
			(net "GND")
			(options
				(clearance outline)
				(anchor circle)
			)
			(primitives
				(gr_poly
					(pts
						(arc
							(start -0.1778 0.5715)
							(mid -0.321484 0.511984)
							(end -0.381 0.3683)
						)
						(arc
							(start -0.381 -0.3683)
							(mid -0.321484 -0.511984)
							(end -0.1778 -0.5715)
						)
						(arc
							(start 0.1778 -0.5715)
							(mid 0.321484 -0.511984)
							(end 0.381 -0.3683)
						)
						(arc
							(start 0.381 0.3683)
							(mid 0.321484 0.511984)
							(end 0.1778 0.5715)
						)
					)
					(width 0)
					(fill yes)
				)
			)
		)
	)
	(footprint ""
		(layer "F.Cu")
		(at 191.850772 -45.479462 -90)
		(property "Reference" "R180"
			(at 0 0 270)
			(layer "F.SilkS")
			(hide yes)
			(effects
				(font
					(size 1.27 1.27)
				)
			)
		)
		(property "Value" "2K2R2F-GP"
			(at 0.064008 -3.993896 270)
			(unlocked yes)
			(layer "F.Fab")
			(hide yes)
			(effects
				(font
					(size 1.016 1.016)
					(thickness 0.1524)
				)
			)
		)
		(property "Device Type" "R402H16"
			(at 0.064008 -5.517896 270)
			(unlocked yes)
			(layer "F.Fab")
			(hide yes)
			(effects
				(font
					(size 1.016 1.016)
					(thickness 0.1524)
				)
			)
		)
		(duplicate_pad_numbers_are_jumpers no)
		(fp_line
			(start -0.508 -0.9398)
			(end -0.508 0.9398)
			(stroke
				(width 0.1524)
				(type default)
			)
			(layer "F.SilkS")
		)
		(fp_line
			(start 0.508 -0.9398)
			(end -0.508 -0.9398)
			(stroke
				(width 0.1524)
				(type default)
			)
			(layer "F.SilkS")
		)
		(fp_rect
			(start -0.508 0.9398)
			(end 0.508 -0.9398)
			(stroke
				(width 0)
				(type default)
			)
			(fill no)
			(layer "F.CrtYd")
		)
		(fp_rect
			(start -0.508 0.9398)
			(end 0.508 -0.9398)
			(stroke
				(width 0)
				(type default)
			)
			(fill no)
			(layer "F.Fab")
		)
		(pad "1" smd custom
			(at 0 -0.4445 270)
			(size 0.1397 0.1397)
			(layers "F.Cu" "F.Mask" "F.Paste")
			(net "P1V8_C")
			(options
				(clearance outline)
				(anchor circle)
			)
			(primitives
				(gr_poly
					(pts
						(arc
							(start -0.1778 -0.2794)
							(mid -0.249642 -0.249642)
							(end -0.2794 -0.1778)
						)
						(arc
							(start -0.2794 0.1778)
							(mid -0.249642 0.249642)
							(end -0.1778 0.2794)
						)
						(arc
							(start 0.1778 0.2794)
							(mid 0.249642 0.249642)
							(end 0.2794 0.1778)
						)
						(arc
							(start 0.2794 -0.1778)
							(mid 0.249642 -0.249642)
							(end 0.1778 -0.2794)
						)
					)
					(width 0)
					(fill yes)
				)
			)
		)
		(pad "2" smd custom
			(at 0 0.4445 270)
			(size 0.1397 0.1397)
			(layers "F.Cu" "F.Mask" "F.Paste")
			(net "SBL_SDA")
			(options
				(clearance outline)
				(anchor circle)
			)
			(primitives
				(gr_poly
					(pts
						(arc
							(start -0.1778 -0.2794)
							(mid -0.249642 -0.249642)
							(end -0.2794 -0.1778)
						)
						(arc
							(start -0.2794 0.1778)
							(mid -0.249642 0.249642)
							(end -0.1778 0.2794)
						)
						(arc
							(start 0.1778 0.2794)
							(mid 0.249642 0.249642)
							(end 0.2794 0.1778)
						)
						(arc
							(start 0.2794 -0.1778)
							(mid 0.249642 -0.249642)
							(end 0.1778 -0.2794)
						)
					)
					(width 0)
					(fill yes)
				)
			)
		)
	)
	(footprint ""
		(layer "F.Cu")
		(at 6.9088 -77.089 180)
		(property "Reference" "R337"
			(at 0 0 180)
			(layer "F.SilkS")
			(hide yes)
			(effects
				(font
					(size 1.27 1.27)
				)
			)
		)
		(property "Value" "4K7R2F-GP"
			(at 0.064008 -3.993896 180)
			(unlocked yes)
			(layer "F.Fab")
			(hide yes)
			(effects
				(font
					(size 1.016 1.016)
					(thickness 0.1524)
				)
			)
		)
		(property "Device Type" "R402H16"
			(at 0.064008 -5.517896 180)
			(unlocked yes)
			(layer "F.Fab")
			(hide yes)
			(effects
				(font
					(size 1.016 1.016)
					(thickness 0.1524)
				)
			)
		)
		(duplicate_pad_numbers_are_jumpers no)
		(fp_line
			(start 0.508 -0.9398)
			(end -0.508 -0.9398)
			(stroke
				(width 0.1524)
				(type default)
			)
			(layer "F.SilkS")
		)
		(fp_line
			(start -0.508 -0.9398)
			(end -0.508 0.9398)
			(stroke
				(width 0.1524)
				(type default)
			)
			(layer "F.SilkS")
		)
		(fp_rect
			(start -0.508 0.9398)
			(end 0.508 -0.9398)
			(stroke
				(width 0)
				(type default)
			)
			(fill no)
			(layer "F.CrtYd")
		)
		(fp_rect
			(start -0.508 0.9398)
			(end 0.508 -0.9398)
			(stroke
				(width 0)
				(type default)
			)
			(fill no)
			(layer "F.Fab")
		)
		(pad "1" smd custom
			(at 0 -0.4445 180)
			(size 0.1397 0.1397)
			(layers "F.Cu" "F.Mask" "F.Paste")
			(net "P3V3")
			(options
				(clearance outline)
				(anchor circle)
			)
			(primitives
				(gr_poly
					(pts
						(arc
							(start -0.1778 -0.2794)
							(mid -0.249642 -0.249642)
							(end -0.2794 -0.1778)
						)
						(arc
							(start -0.2794 0.1778)
							(mid -0.249642 0.249642)
							(end -0.1778 0.2794)
						)
						(arc
							(start 0.1778 0.2794)
							(mid 0.249642 0.249642)
							(end 0.2794 0.1778)
						)
						(arc
							(start 0.2794 -0.1778)
							(mid 0.249642 -0.249642)
							(end 0.1778 -0.2794)
						)
					)
					(width 0)
					(fill yes)
				)
			)
		)
		(pad "2" smd custom
			(at 0 0.4445 180)
			(size 0.1397 0.1397)
			(layers "F.Cu" "F.Mask" "F.Paste")
			(net "EXP_EEPROM_A2")
			(options
				(clearance outline)
				(anchor circle)
			)
			(primitives
				(gr_poly
					(pts
						(arc
							(start -0.1778 -0.2794)
							(mid -0.249642 -0.249642)
							(end -0.2794 -0.1778)
						)
						(arc
							(start -0.2794 0.1778)
							(mid -0.249642 0.249642)
							(end -0.1778 0.2794)
						)
						(arc
							(start 0.1778 0.2794)
							(mid 0.249642 0.249642)
							(end 0.2794 0.1778)
						)
						(arc
							(start 0.2794 -0.1778)
							(mid 0.249642 -0.249642)
							(end 0.1778 -0.2794)
						)
					)
					(width 0)
					(fill yes)
				)
			)
		)
	)
	(footprint ""
		(layer "F.Cu")
		(at 162.961066 -58.13806)
		(property "Reference" "R266"
			(at 0 0 0)
			(layer "F.SilkS")
			(hide yes)
			(effects
				(font
					(size 1.27 1.27)
				)
			)
		)
		(property "Value" "4K7R2F-GP"
			(at 0.064008 -3.993896 0)
			(unlocked yes)
			(layer "F.Fab")
			(hide yes)
			(effects
				(font
					(size 1.016 1.016)
					(thickness 0.1524)
				)
			)
		)
		(property "Device Type" "R402H16"
			(at 0.064008 -5.517896 0)
			(unlocked yes)
			(layer "F.Fab")
			(hide yes)
			(effects
				(font
					(size 1.016 1.016)
					(thickness 0.1524)
				)
			)
		)
		(duplicate_pad_numbers_are_jumpers no)
		(fp_line
			(start -0.508 -0.9398)
			(end -0.508 0.9398)
			(stroke
				(width 0.1524)
				(type default)
			)
			(layer "F.SilkS")
		)
		(fp_line
			(start 0.508 -0.9398)
			(end -0.508 -0.9398)
			(stroke
				(width 0.1524)
				(type default)
			)
			(layer "F.SilkS")
		)
		(fp_rect
			(start -0.508 0.9398)
			(end 0.508 -0.9398)
			(stroke
				(width 0)
				(type default)
			)
			(fill no)
			(layer "F.CrtYd")
		)
		(fp_rect
			(start -0.508 0.9398)
			(end 0.508 -0.9398)
			(stroke
				(width 0)
				(type default)
			)
			(fill no)
			(layer "F.Fab")
		)
		(pad "1" smd custom
			(at 0 -0.4445)
			(size 0.1397 0.1397)
			(layers "F.Cu" "F.Mask" "F.Paste")
			(net "P1V8_C")
			(options
				(clearance outline)
				(anchor circle)
			)
			(primitives
				(gr_poly
					(pts
						(arc
							(start -0.1778 -0.2794)
							(mid -0.249642 -0.249642)
							(end -0.2794 -0.1778)
						)
						(arc
							(start -0.2794 0.1778)
							(mid -0.249642 0.249642)
							(end -0.1778 0.2794)
						)
						(arc
							(start 0.1778 0.2794)
							(mid 0.249642 0.249642)
							(end 0.2794 0.1778)
						)
						(arc
							(start 0.2794 -0.1778)
							(mid 0.249642 -0.249642)
							(end 0.1778 -0.2794)
						)
					)
					(width 0)
					(fill yes)
				)
			)
		)
		(pad "2" smd custom
			(at 0 0.4445)
			(size 0.1397 0.1397)
			(layers "F.Cu" "F.Mask" "F.Paste")
			(net "ICE0_TMS")
			(options
				(clearance outline)
				(anchor circle)
			)
			(primitives
				(gr_poly
					(pts
						(arc
							(start -0.1778 -0.2794)
							(mid -0.249642 -0.249642)
							(end -0.2794 -0.1778)
						)
						(arc
							(start -0.2794 0.1778)
							(mid -0.249642 0.249642)
							(end -0.1778 0.2794)
						)
						(arc
							(start 0.1778 0.2794)
							(mid 0.249642 0.249642)
							(end 0.2794 0.1778)
						)
						(arc
							(start 0.2794 -0.1778)
							(mid 0.249642 -0.249642)
							(end 0.1778 -0.2794)
						)
					)
					(width 0)
					(fill yes)
				)
			)
		)
	)
	(footprint ""
		(layer "F.Cu")
		(at 174.3202 -93.5482)
		(property "Reference" "C623"
			(at 0 0 0)
			(layer "F.SilkS")
			(hide yes)
			(effects
				(font
					(size 1.27 1.27)
				)
			)
		)
		(property "Value" "SC1U25V3KX-GP"
			(at 0 -2.8194 0)
			(unlocked yes)
			(layer "F.Fab")
			(hide yes)
			(effects
				(font
					(size 1.016 1.016)
					(thickness 0.1524)
				)
			)
		)
		(property "Device Type" "C603H36"
			(at 0 -4.3434 0)
			(unlocked yes)
			(layer "F.Fab")
			(hide yes)
			(effects
				(font
					(size 1.016 1.016)
					(thickness 0.1524)
				)
			)
		)
		(duplicate_pad_numbers_are_jumpers no)
		(fp_line
			(start 0.508 0)
			(end -0.508 0)
			(stroke
				(width 0.2032)
				(type default)
			)
			(layer "F.SilkS")
		)
		(fp_rect
			(start -0.5842 1.3335)
			(end 0.5842 -1.3335)
			(stroke
				(width 0)
				(type default)
			)
			(fill no)
			(layer "F.CrtYd")
		)
		(fp_rect
			(start -0.5842 1.3335)
			(end 0.5842 -1.3335)
			(stroke
				(width 0)
				(type default)
			)
			(fill no)
			(layer "F.Fab")
		)
		(pad "1" smd custom
			(at 0 -0.762)
			(size 0.2159 0.2159)
			(layers "F.Cu" "F.Mask" "F.Paste")
			(net "VT235_BST")
			(options
				(clearance outline)
				(anchor circle)
			)
			(primitives
				(gr_poly
					(pts
						(arc
							(start -0.3302 -0.4318)
							(mid -0.402042 -0.402042)
							(end -0.4318 -0.3302)
						)
						(arc
							(start -0.4318 0.3302)
							(mid -0.402042 0.402042)
							(end -0.3302 0.4318)
						)
						(arc
							(start 0.3302 0.4318)
							(mid 0.402042 0.402042)
							(end 0.4318 0.3302)
						)
						(arc
							(start 0.4318 -0.3302)
							(mid 0.402042 -0.402042)
							(end 0.3302 -0.4318)
						)
					)
					(width 0)
					(fill yes)
				)
			)
		)
		(pad "2" smd custom
			(at 0 0.762)
			(size 0.2159 0.2159)
			(layers "F.Cu" "F.Mask" "F.Paste")
			(net "VT235_VX")
			(options
				(clearance outline)
				(anchor circle)
			)
			(primitives
				(gr_poly
					(pts
						(arc
							(start -0.3302 -0.4318)
							(mid -0.402042 -0.402042)
							(end -0.4318 -0.3302)
						)
						(arc
							(start -0.4318 0.3302)
							(mid -0.402042 0.402042)
							(end -0.3302 0.4318)
						)
						(arc
							(start 0.3302 0.4318)
							(mid 0.402042 0.402042)
							(end 0.4318 0.3302)
						)
						(arc
							(start 0.4318 -0.3302)
							(mid 0.402042 -0.402042)
							(end 0.3302 -0.4318)
						)
					)
					(width 0)
					(fill yes)
				)
			)
		)
	)
	(footprint ""
		(layer "F.Cu")
		(at 26.65222 -30.93974)
		(property "Reference" "C566"
			(at 0 0 0)
			(layer "F.SilkS")
			(hide yes)
			(effects
				(font
					(size 1.27 1.27)
				)
			)
		)
		(property "Value" "SC10U16V5KX-7-GP-U"
			(at -0.0762 -6.1214 0)
			(unlocked yes)
			(layer "F.Fab")
			(hide yes)
			(effects
				(font
					(size 1.016 1.016)
					(thickness 0.1524)
				)
			)
		)
		(property "Device Type" "C805H58"
			(at -0.0762 -8.1534 0)
			(unlocked yes)
			(layer "F.Fab")
			(hide yes)
			(effects
				(font
					(size 1.016 1.016)
					(thickness 0.1524)
				)
			)
		)
		(duplicate_pad_numbers_are_jumpers no)
		(fp_line
			(start 0.635 0)
			(end -0.635 0)
			(stroke
				(width 0.508)
				(type default)
			)
			(layer "F.SilkS")
		)
		(fp_rect
			(start -0.9652 1.778)
			(end 0.9652 -1.778)
			(stroke
				(width 0)
				(type default)
			)
			(fill no)
			(layer "F.CrtYd")
		)
		(fp_poly
			(pts
				(xy -0.9652 -1.778) (xy 0.9652 -1.778) (xy 0.9652 1.778) (xy -0.9652 1.778)
			)
			(stroke
				(width 0)
				(type default)
			)
			(fill no)
			(layer "F.Fab")
		)
		(pad "1" smd rect
			(at 0 -0.9652)
			(size 1.397 1.143)
			(layers "F.Cu" "F.Mask" "F.Paste")
			(net "P12V_MAIN")
		)
		(pad "2" smd rect
			(at 0 0.9652)
			(size 1.397 1.143)
			(layers "F.Cu" "F.Mask" "F.Paste")
			(net "GND")
		)
	)
	(footprint ""
		(layer "F.Cu")
		(at 160.274 -85.725 90)
		(property "Reference" "C519"
			(at 0 0 90)
			(layer "F.SilkS")
			(hide yes)
			(effects
				(font
					(size 1.27 1.27)
				)
			)
		)
		(property "Value" "SCD1U16V2KX-3GP"
			(at 1.1811 -2.7051 90)
			(unlocked yes)
			(layer "F.Fab")
			(hide yes)
			(effects
				(font
					(size 1.016 1.016)
					(thickness 0.1524)
				)
			)
		)
		(property "Device Type" "C402H22"
			(at 1.1811 -4.2291 90)
			(unlocked yes)
			(layer "F.Fab")
			(hide yes)
			(effects
				(font
					(size 1.016 1.016)
					(thickness 0.1524)
				)
			)
		)
		(duplicate_pad_numbers_are_jumpers no)
		(fp_rect
			(start -0.4318 0.9525)
			(end 0.4318 -0.9525)
			(stroke
				(width 0)
				(type default)
			)
			(fill no)
			(layer "F.CrtYd")
		)
		(fp_rect
			(start -0.4318 0.9525)
			(end 0.4318 -0.9525)
			(stroke
				(width 0)
				(type default)
			)
			(fill no)
			(layer "F.Fab")
		)
		(pad "1" smd custom
			(at 0 -0.4445 90)
			(size 0.1524 0.1524)
			(layers "F.Cu" "F.Mask" "F.Paste")
			(net "P3V3")
			(options
				(clearance outline)
				(anchor circle)
			)
			(primitives
				(gr_poly
					(pts
						(arc
							(start 0.3048 -0.2032)
							(mid 0.275042 -0.275042)
							(end 0.2032 -0.3048)
						)
						(arc
							(start -0.2032 -0.3048)
							(mid -0.275042 -0.275042)
							(end -0.3048 -0.2032)
						)
						(arc
							(start -0.3048 0.2032)
							(mid -0.275042 0.275042)
							(end -0.2032 0.3048)
						)
						(arc
							(start 0.2032 0.3048)
							(mid 0.275042 0.275042)
							(end 0.3048 0.2032)
						)
					)
					(width 0)
					(fill yes)
				)
			)
		)
		(pad "2" smd custom
			(at 0 0.4445 90)
			(size 0.1524 0.1524)
			(layers "F.Cu" "F.Mask" "F.Paste")
			(net "GND")
			(options
				(clearance outline)
				(anchor circle)
			)
			(primitives
				(gr_poly
					(pts
						(arc
							(start 0.3048 -0.2032)
							(mid 0.275042 -0.275042)
							(end 0.2032 -0.3048)
						)
						(arc
							(start -0.2032 -0.3048)
							(mid -0.275042 -0.275042)
							(end -0.3048 -0.2032)
						)
						(arc
							(start -0.3048 0.2032)
							(mid -0.275042 0.275042)
							(end -0.2032 0.3048)
						)
						(arc
							(start 0.2032 0.3048)
							(mid 0.275042 0.275042)
							(end 0.3048 0.2032)
						)
					)
					(width 0)
					(fill yes)
				)
			)
		)
	)
)
